(kicad_pcb
	(version 20241229)
	(generator "pcbnew")
	(generator_version "9.0")
	(general
		(thickness 1.599998)
		(legacy_teardrops no)
	)
	(paper "A4")
	(title_block
		(title "Artix - Datacenter Secure Control Module (DC-SCM)")
		(date "2024-11-06")
		(rev "1.1.3")
		(comment 9 "footprints 324-328 of 544")
	)
	(layers
		(0 "F.Cu" signal)
		(4 "In1.Cu" signal)
		(6 "In2.Cu" signal)
		(8 "In3.Cu" signal)
		(10 "In4.Cu" signal)
		(12 "In5.Cu" signal)
		(14 "In6.Cu" signal)
		(2 "B.Cu" signal)
		(9 "F.Adhes" user "F.Adhesive")
		(11 "B.Adhes" user "B.Adhesive")
		(13 "F.Paste" user)
		(15 "B.Paste" user)
		(5 "F.SilkS" user "F.Silkscreen")
		(7 "B.SilkS" user "B.Silkscreen")
		(1 "F.Mask" user)
		(3 "B.Mask" user)
		(17 "Dwgs.User" user "User.Drawings")
		(19 "Cmts.User" user "User.Comments")
		(21 "Eco1.User" user "User.Eco1")
		(23 "Eco2.User" user "User.Eco2")
		(25 "Edge.Cuts" user)
		(27 "Margin" user)
		(31 "F.CrtYd" user "F.Courtyard")
		(29 "B.CrtYd" user "B.Courtyard")
		(35 "F.Fab" user)
		(33 "B.Fab" user)
	)
	(footprint "antmicro-footprints:SOT-23-3"
		(layer "B.Cu")
		(at 71.04 80.74 90)
		(property "Reference" "Q13"
			(at 1.04 -2.64 180)
			(layer "B.SilkS")
			(effects
				(font
					(size 0.7 0.7)
					(thickness 0.15)
				)
				(justify right bottom mirror)
			)
		)
		(property "Value" "2N7002_SOT-23-3"
			(at -1.9 -2.7 90)
			(layer "B.Fab")
			(effects
				(font
					(size 0.7 0.7)
					(thickness 0.15)
				)
				(justify right bottom mirror)
			)
		)
		(property "Datasheet" "https://www.onsemi.com/pub/Collateral/NDS7002A-D.PDF"
			(at 0 0 90)
			(layer "F.Fab")
			(hide yes)
			(effects
				(font
					(size 1.27 1.27)
					(thickness 0.15)
				)
			)
		)
		(property "Description" "Power MOSFET, N Channel, 60 V, 115 mA, 1.2 ohm, SOT-23, Surface Mount"
			(at 0 0 90)
			(layer "F.Fab")
			(hide yes)
			(effects
				(font
					(size 1.27 1.27)
					(thickness 0.15)
				)
			)
		)
		(property "Author" "Antmicro"
			(at 151.78 9.7 0)
			(layer "B.Fab")
			(hide yes)
			(effects
				(font
					(size 1 1)
					(thickness 0.15)
				)
				(justify mirror)
			)
		)
		(property "License" "Apache-2.0"
			(at 151.78 9.7 0)
			(layer "B.Fab")
			(hide yes)
			(effects
				(font
					(size 1 1)
					(thickness 0.15)
				)
				(justify mirror)
			)
		)
		(property "MPN" "2N7002"
			(at 151.78 9.7 0)
			(layer "B.Fab")
			(hide yes)
			(effects
				(font
					(size 1 1)
					(thickness 0.15)
				)
				(justify mirror)
			)
		)
		(property "Manufacturer" "ON Semiconductor"
			(at 151.78 9.7 0)
			(layer "B.Fab")
			(hide yes)
			(effects
				(font
					(size 1 1)
					(thickness 0.15)
				)
				(justify mirror)
			)
		)
		(sheetname "/FPGA banks 34-35 & CFG/")
		(sheetfile "fpga-banks-34-25-cfg.kicad_sch")
		(attr smd)
		(fp_line
			(start 0.7 -1.5)
			(end -0.7 -1.5)
			(stroke
				(width 0.15)
				(type solid)
			)
			(layer "B.SilkS")
		)
		(fp_line
			(start -0.7 -1.5)
			(end -0.7 -1.35)
			(stroke
				(width 0.15)
				(type solid)
			)
			(layer "B.SilkS")
		)
		(fp_line
			(start 0.7 -0.4)
			(end 0.7 -1.5)
			(stroke
				(width 0.15)
				(type solid)
			)
			(layer "B.SilkS")
		)
		(fp_line
			(start 0.7 0.4)
			(end 0.7 1.5)
			(stroke
				(width 0.15)
				(type solid)
			)
			(layer "B.SilkS")
		)
		(fp_line
			(start -0.85 1.35)
			(end -0.7 1.5)
			(stroke
				(width 0.15)
				(type solid)
			)
			(layer "B.SilkS")
		)
		(fp_line
			(start -1.45 1.35)
			(end -0.85 1.35)
			(stroke
				(width 0.15)
				(type solid)
			)
			(layer "B.SilkS")
		)
		(fp_line
			(start 0.7 1.5)
			(end -0.7 1.5)
			(stroke
				(width 0.15)
				(type solid)
			)
			(layer "B.SilkS")
		)
		(fp_line
			(start 0.85 -1.65)
			(end -0.85 -1.65)
			(stroke
				(width 0.05)
				(type solid)
			)
			(layer "B.CrtYd")
		)
		(fp_line
			(start -0.85 -1.65)
			(end -0.85 -1.4)
			(stroke
				(width 0.05)
				(type solid)
			)
			(layer "B.CrtYd")
		)
		(fp_line
			(start -0.85 -1.4)
			(end -1.75 -1.4)
			(stroke
				(width 0.05)
				(type solid)
			)
			(layer "B.CrtYd")
		)
		(fp_line
			(start -1.75 -1.4)
			(end -1.75 -0.5)
			(stroke
				(width 0.05)
				(type solid)
			)
			(layer "B.CrtYd")
		)
		(fp_line
			(start -0.85 -0.5)
			(end -0.85 0.5)
			(stroke
				(width 0.05)
				(type solid)
			)
			(layer "B.CrtYd")
		)
		(fp_line
			(start -1.75 -0.5)
			(end -0.85 -0.5)
			(stroke
				(width 0.05)
				(type solid)
			)
			(layer "B.CrtYd")
		)
		(fp_line
			(start 1.75 -0.45)
			(end 0.85 -0.45)
			(stroke
				(width 0.05)
				(type solid)
			)
			(layer "B.CrtYd")
		)
		(fp_line
			(start 0.85 -0.45)
			(end 0.85 -1.65)
			(stroke
				(width 0.05)
				(type solid)
			)
			(layer "B.CrtYd")
		)
		(fp_line
			(start 1.75 0.45)
			(end 1.75 -0.45)
			(stroke
				(width 0.05)
				(type solid)
			)
			(layer "B.CrtYd")
		)
		(fp_line
			(start 0.825 0.45)
			(end 1.75 0.45)
			(stroke
				(width 0.05)
				(type solid)
			)
			(layer "B.CrtYd")
		)
		(fp_line
			(start -0.85 0.5)
			(end -1.75 0.5)
			(stroke
				(width 0.05)
				(type solid)
			)
			(layer "B.CrtYd")
		)
		(fp_line
			(start -1.75 0.5)
			(end -1.75 1.4)
			(stroke
				(width 0.05)
				(type solid)
			)
			(layer "B.CrtYd")
		)
		(fp_line
			(start -0.9 1.4)
			(end -1.75 1.4)
			(stroke
				(width 0.05)
				(type solid)
			)
			(layer "B.CrtYd")
		)
		(fp_line
			(start 0.825 1.6)
			(end 0.825 0.45)
			(stroke
				(width 0.05)
				(type solid)
			)
			(layer "B.CrtYd")
		)
		(fp_line
			(start -0.9 1.6)
			(end -0.9 1.4)
			(stroke
				(width 0.05)
				(type solid)
			)
			(layer "B.CrtYd")
		)
		(fp_line
			(start -0.9 1.6)
			(end 0.825 1.6)
			(stroke
				(width 0.05)
				(type solid)
			)
			(layer "B.CrtYd")
		)
		(fp_line
			(start 0.688 -1.519)
			(end 0.688 1.52)
			(stroke
				(width 0.15)
				(type solid)
			)
			(layer "B.Fab")
		)
		(fp_line
			(start -0.712 -1.519)
			(end 0.688 -1.519)
			(stroke
				(width 0.15)
				(type solid)
			)
			(layer "B.Fab")
		)
		(fp_line
			(start -0.712 1.325)
			(end -0.712 -1.523)
			(stroke
				(width 0.15)
				(type solid)
			)
			(layer "B.Fab")
		)
		(fp_line
			(start -0.437 1.526)
			(end -0.712 1.325)
			(stroke
				(width 0.15)
				(type solid)
			)
			(layer "B.Fab")
		)
		(fp_line
			(start -0.437 1.526)
			(end 0.688 1.526)
			(stroke
				(width 0.15)
				(type solid)
			)
			(layer "B.Fab")
		)
		(pad "1" smd roundrect
			(at -1.1 0.951 90)
			(size 1 0.6)
			(layers "B.Cu" "B.Mask" "B.Paste")
			(roundrect_rratio 0.15)
			(net 220 "DONE")
			(pinfunction "G")
			(pintype "input")
		)
		(pad "2" smd roundrect
			(at -1.1 -0.949 90)
			(size 1 0.6)
			(layers "B.Cu" "B.Mask" "B.Paste")
			(roundrect_rratio 0.15)
			(net 1 "GND")
			(pinfunction "S")
			(pintype "passive")
		)
		(pad "3" smd roundrect
			(at 1.1 0.0005 90)
			(size 1 0.6)
			(layers "B.Cu" "B.Mask" "B.Paste")
			(roundrect_rratio 0.15)
			(net 281 "Net-(D10-C)")
			(pinfunction "D")
			(pintype "passive")
		)
	)
	(footprint "antmicro-footprints:R_0402_1005Metric"
		(layer "B.Cu")
		(at 106.835 107.215 -90)
		(descr "Resistor SMD 0402")
		(tags "resistor SMD 0402")
		(property "Reference" "R1"
			(at 0.785 -0.365 90)
			(layer "B.SilkS")
			(effects
				(font
					(size 0.7 0.7)
					(thickness 0.15)
				)
				(justify left bottom mirror)
			)
		)
		(property "Value" "R_1k_0402"
			(at 0 -1.4 90)
			(layer "B.Fab")
			(effects
				(font
					(size 0.7 0.7)
					(thickness 0.15)
				)
				(justify left bottom mirror)
			)
		)
		(property "Datasheet" "https://www.bourns.com/docs/product-datasheets/cr.pdf"
			(at 0 0 270)
			(layer "F.Fab")
			(hide yes)
			(effects
				(font
					(size 1.27 1.27)
					(thickness 0.15)
				)
			)
		)
		(property "Description" "SMD Chip Resistor, 1 kohm, ± 1%, 63 mW, 0402 [1005 Metric], Thick Film, General Purpose"
			(at 0 0 270)
			(layer "F.Fab")
			(hide yes)
			(effects
				(font
					(size 1.27 1.27)
					(thickness 0.15)
				)
			)
		)
		(property "Author" "Antmicro"
			(at -0.38 214.05 0)
			(layer "B.Fab")
			(hide yes)
			(effects
				(font
					(size 1 1)
					(thickness 0.15)
				)
				(justify mirror)
			)
		)
		(property "License" "Apache-2.0"
			(at -0.38 214.05 0)
			(layer "B.Fab")
			(hide yes)
			(effects
				(font
					(size 1 1)
					(thickness 0.15)
				)
				(justify mirror)
			)
		)
		(property "MPN" "CR0402-FX-1001GLF"
			(at -0.38 214.05 0)
			(layer "B.Fab")
			(hide yes)
			(effects
				(font
					(size 1 1)
					(thickness 0.15)
				)
				(justify mirror)
			)
		)
		(property "Manufacturer" "Bourns"
			(at -0.38 214.05 0)
			(layer "B.Fab")
			(hide yes)
			(effects
				(font
					(size 1 1)
					(thickness 0.15)
				)
				(justify mirror)
			)
		)
		(property "Tolerance" "1%"
			(at -0.38 214.05 0)
			(layer "B.Fab")
			(hide yes)
			(effects
				(font
					(size 1 1)
					(thickness 0.15)
				)
				(justify mirror)
			)
		)
		(property "Val" "1k"
			(at -0.38 214.05 0)
			(layer "B.Fab")
			(hide yes)
			(effects
				(font
					(size 1 1)
					(thickness 0.15)
				)
				(justify mirror)
			)
		)
		(sheetname "/FPGA banks 13-16/")
		(sheetfile "fpga-banks-13-16.kicad_sch")
		(attr smd)
		(fp_rect
			(start -0.925 0.47)
			(end 0.925 -0.47)
			(stroke
				(width 0.05)
				(type default)
			)
			(fill no)
			(layer "B.CrtYd")
		)
		(fp_rect
			(start -0.5 0.25)
			(end 0.5 -0.25)
			(stroke
				(width 0.15)
				(type solid)
			)
			(fill no)
			(layer "B.Fab")
		)
		(pad "1" smd roundrect
			(at -0.48 0 270)
			(size 0.59 0.64)
			(layers "B.Cu" "B.Mask" "B.Paste")
			(roundrect_rratio 0.25)
			(net 2 "VCC3V3")
			(pintype "passive")
		)
		(pad "2" smd roundrect
			(at 0.48 0 270)
			(size 0.59 0.64)
			(layers "B.Cu" "B.Mask" "B.Paste")
			(roundrect_rratio 0.25)
			(net 260 "/FPGA banks 13-16/PUDC_B")
			(pintype "passive")
		)
	)
	(footprint "antmicro-footprints:R_0402_1005Metric"
		(layer "B.Cu")
		(at 107.855 107.225 90)
		(descr "Resistor SMD 0402")
		(tags "resistor SMD 0402")
		(property "Reference" "R2"
			(at -2.275 0.345 90)
			(layer "B.SilkS")
			(effects
				(font
					(size 0.7 0.7)
					(thickness 0.15)
				)
				(justify right bottom mirror)
			)
		)
		(property "Value" "R_1k_0402"
			(at 0 -1.4 90)
			(layer "B.Fab")
			(effects
				(font
					(size 0.7 0.7)
					(thickness 0.15)
				)
				(justify right bottom mirror)
			)
		)
		(property "Datasheet" "https://www.bourns.com/docs/product-datasheets/cr.pdf"
			(at 0 0 90)
			(layer "F.Fab")
			(hide yes)
			(effects
				(font
					(size 1.27 1.27)
					(thickness 0.15)
				)
			)
		)
		(property "Description" "SMD Chip Resistor, 1 kohm, ± 1%, 63 mW, 0402 [1005 Metric], Thick Film, General Purpose"
			(at 0 0 90)
			(layer "F.Fab")
			(hide yes)
			(effects
				(font
					(size 1.27 1.27)
					(thickness 0.15)
				)
			)
		)
		(property "Author" "Antmicro"
			(at 215.08 -0.63 0)
			(layer "B.Fab")
			(hide yes)
			(effects
				(font
					(size 1 1)
					(thickness 0.15)
				)
				(justify mirror)
			)
		)
		(property "License" "Apache-2.0"
			(at 215.08 -0.63 0)
			(layer "B.Fab")
			(hide yes)
			(effects
				(font
					(size 1 1)
					(thickness 0.15)
				)
				(justify mirror)
			)
		)
		(property "MPN" "CR0402-FX-1001GLF"
			(at 215.08 -0.63 0)
			(layer "B.Fab")
			(hide yes)
			(effects
				(font
					(size 1 1)
					(thickness 0.15)
				)
				(justify mirror)
			)
		)
		(property "Manufacturer" "Bourns"
			(at 215.08 -0.63 0)
			(layer "B.Fab")
			(hide yes)
			(effects
				(font
					(size 1 1)
					(thickness 0.15)
				)
				(justify mirror)
			)
		)
		(property "Tolerance" "1%"
			(at 215.08 -0.63 0)
			(layer "B.Fab")
			(hide yes)
			(effects
				(font
					(size 1 1)
					(thickness 0.15)
				)
				(justify mirror)
			)
		)
		(property "Val" "1k"
			(at 215.08 -0.63 0)
			(layer "B.Fab")
			(hide yes)
			(effects
				(font
					(size 1 1)
					(thickness 0.15)
				)
				(justify mirror)
			)
		)
		(property "DNP" ""
			(at 0 0 90)
			(unlocked yes)
			(layer "B.Fab")
			(hide yes)
			(effects
				(font
					(size 1 1)
					(thickness 0.15)
				)
				(justify mirror)
			)
		)
		(sheetname "/FPGA banks 13-16/")
		(sheetfile "fpga-banks-13-16.kicad_sch")
		(attr smd)
		(fp_rect
			(start -0.925 0.47)
			(end 0.925 -0.47)
			(stroke
				(width 0.05)
				(type default)
			)
			(fill no)
			(layer "B.CrtYd")
		)
		(fp_rect
			(start -0.5 0.25)
			(end 0.5 -0.25)
			(stroke
				(width 0.15)
				(type solid)
			)
			(fill no)
			(layer "B.Fab")
		)
		(pad "1" smd roundrect
			(at -0.48 0 90)
			(size 0.59 0.64)
			(layers "B.Cu" "B.Mask" "B.Paste")
			(roundrect_rratio 0.25)
			(net 260 "/FPGA banks 13-16/PUDC_B")
			(pintype "passive")
		)
		(pad "2" smd roundrect
			(at 0.48 0 90)
			(size 0.59 0.64)
			(layers "B.Cu" "B.Mask" "B.Paste")
			(roundrect_rratio 0.25)
			(net 1 "GND")
			(pintype "passive")
		)
	)
	(footprint "antmicro-footprints:R_0402_1005Metric"
		(layer "B.Cu")
		(at 68.09 87.315)
		(descr "Resistor SMD 0402")
		(tags "resistor SMD 0402")
		(property "Reference" "R128"
			(at -3.59 0.36 0)
			(layer "B.SilkS")
			(effects
				(font
					(size 0.7 0.7)
					(thickness 0.15)
				)
				(justify right bottom mirror)
			)
		)
		(property "Value" "R_1k_0402"
			(at 0 -1.4 0)
			(layer "B.Fab")
			(effects
				(font
					(size 0.7 0.7)
					(thickness 0.15)
				)
				(justify right bottom mirror)
			)
		)
		(property "Datasheet" "https://www.bourns.com/docs/product-datasheets/cr.pdf"
			(at 0 0 0)
			(layer "F.Fab")
			(hide yes)
			(effects
				(font
					(size 1.27 1.27)
					(thickness 0.15)
				)
			)
		)
		(property "Description" "SMD Chip Resistor, 1 kohm, ± 1%, 63 mW, 0402 [1005 Metric], Thick Film, General Purpose"
			(at 0 0 0)
			(layer "F.Fab")
			(hide yes)
			(effects
				(font
					(size 1.27 1.27)
					(thickness 0.15)
				)
			)
		)
		(property "Author" "Antmicro"
			(at 0 0 0)
			(layer "B.Fab")
			(hide yes)
			(effects
				(font
					(size 1 1)
					(thickness 0.15)
				)
				(justify mirror)
			)
		)
		(property "License" "Apache-2.0"
			(at 0 0 0)
			(layer "B.Fab")
			(hide yes)
			(effects
				(font
					(size 1 1)
					(thickness 0.15)
				)
				(justify mirror)
			)
		)
		(property "MPN" "CR0402-FX-1001GLF"
			(at 0 0 0)
			(layer "B.Fab")
			(hide yes)
			(effects
				(font
					(size 1 1)
					(thickness 0.15)
				)
				(justify mirror)
			)
		)
		(property "Manufacturer" "Bourns"
			(at 0 0 0)
			(layer "B.Fab")
			(hide yes)
			(effects
				(font
					(size 1 1)
					(thickness 0.15)
				)
				(justify mirror)
			)
		)
		(property "Tolerance" "1%"
			(at 0 0 0)
			(layer "B.Fab")
			(hide yes)
			(effects
				(font
					(size 1 1)
					(thickness 0.15)
				)
				(justify mirror)
			)
		)
		(property "Val" "1k"
			(at 0 0 0)
			(layer "B.Fab")
			(hide yes)
			(effects
				(font
					(size 1 1)
					(thickness 0.15)
				)
				(justify mirror)
			)
		)
		(sheetname "/FPGA banks 34-35 & CFG/")
		(sheetfile "fpga-banks-34-25-cfg.kicad_sch")
		(attr smd)
		(fp_rect
			(start -0.925 0.47)
			(end 0.925 -0.47)
			(stroke
				(width 0.05)
				(type default)
			)
			(fill no)
			(layer "B.CrtYd")
		)
		(fp_rect
			(start -0.5 0.25)
			(end 0.5 -0.25)
			(stroke
				(width 0.15)
				(type solid)
			)
			(fill no)
			(layer "B.Fab")
		)
		(pad "1" smd roundrect
			(at -0.48 0)
			(size 0.59 0.64)
			(layers "B.Cu" "B.Mask" "B.Paste")
			(roundrect_rratio 0.25)
			(net 279 "Net-(D9-A)")
			(pintype "passive")
		)
		(pad "2" smd roundrect
			(at 0.48 0)
			(size 0.59 0.64)
			(layers "B.Cu" "B.Mask" "B.Paste")
			(roundrect_rratio 0.25)
			(net 2 "VCC3V3")
			(pintype "passive")
		)
	)
	(footprint "antmicro-footprints:R_0402_1005Metric"
		(layer "B.Cu")
		(at 68.09 85.24)
		(descr "Resistor SMD 0402")
		(tags "resistor SMD 0402")
		(property "Reference" "R129"
			(at -3.59 0.36 0)
			(layer "B.SilkS")
			(effects
				(font
					(size 0.7 0.7)
					(thickness 0.15)
				)
				(justify right bottom mirror)
			)
		)
		(property "Value" "R_1k_0402"
			(at 0 -1.4 0)
			(layer "B.Fab")
			(effects
				(font
					(size 0.7 0.7)
					(thickness 0.15)
				)
				(justify right bottom mirror)
			)
		)
		(property "Datasheet" "https://www.bourns.com/docs/product-datasheets/cr.pdf"
			(at 0 0 0)
			(layer "F.Fab")
			(hide yes)
			(effects
				(font
					(size 1.27 1.27)
					(thickness 0.15)
				)
			)
		)
		(property "Description" "SMD Chip Resistor, 1 kohm, ± 1%, 63 mW, 0402 [1005 Metric], Thick Film, General Purpose"
			(at 0 0 0)
			(layer "F.Fab")
			(hide yes)
			(effects
				(font
					(size 1.27 1.27)
					(thickness 0.15)
				)
			)
		)
		(property "Author" "Antmicro"
			(at 0 0 0)
			(layer "B.Fab")
			(hide yes)
			(effects
				(font
					(size 1 1)
					(thickness 0.15)
				)
				(justify mirror)
			)
		)
		(property "License" "Apache-2.0"
			(at 0 0 0)
			(layer "B.Fab")
			(hide yes)
			(effects
				(font
					(size 1 1)
					(thickness 0.15)
				)
				(justify mirror)
			)
		)
		(property "MPN" "CR0402-FX-1001GLF"
			(at 0 0 0)
			(layer "B.Fab")
			(hide yes)
			(effects
				(font
					(size 1 1)
					(thickness 0.15)
				)
				(justify mirror)
			)
		)
		(property "Manufacturer" "Bourns"
			(at 0 0 0)
			(layer "B.Fab")
			(hide yes)
			(effects
				(font
					(size 1 1)
					(thickness 0.15)
				)
				(justify mirror)
			)
		)
		(property "Tolerance" "1%"
			(at 0 0 0)
			(layer "B.Fab")
			(hide yes)
			(effects
				(font
					(size 1 1)
					(thickness 0.15)
				)
				(justify mirror)
			)
		)
		(property "Val" "1k"
			(at 0 0 0)
			(layer "B.Fab")
			(hide yes)
			(effects
				(font
					(size 1 1)
					(thickness 0.15)
				)
				(justify mirror)
			)
		)
		(sheetname "/FPGA banks 34-35 & CFG/")
		(sheetfile "fpga-banks-34-25-cfg.kicad_sch")
		(attr smd)
		(fp_rect
			(start -0.925 0.47)
			(end 0.925 -0.47)
			(stroke
				(width 0.05)
				(type default)
			)
			(fill no)
			(layer "B.CrtYd")
		)
		(fp_rect
			(start -0.5 0.25)
			(end 0.5 -0.25)
			(stroke
				(width 0.15)
				(type solid)
			)
			(fill no)
			(layer "B.Fab")
		)
		(pad "1" smd roundrect
			(at -0.48 0)
			(size 0.59 0.64)
			(layers "B.Cu" "B.Mask" "B.Paste")
			(roundrect_rratio 0.25)
			(net 283 "Net-(D10-A)")
			(pintype "passive")
		)
		(pad "2" smd roundrect
			(at 0.48 0)
			(size 0.59 0.64)
			(layers "B.Cu" "B.Mask" "B.Paste")
			(roundrect_rratio 0.25)
			(net 2 "VCC3V3")
			(pintype "passive")
		)
	)
)
